(kicad_pcb
	(version 20241229)
	(generator "pcbnew")
	(generator_version "9.0")
	(general
		(thickness 1.552)
		(legacy_teardrops no)
	)
	(paper "A4")
	(title_block
		(date "2023-07-25")
		(rev "1.1.4")
		(comment 9 "footprints 192-194 of 379")
	)
	(layers
		(0 "F.Cu" signal)
		(4 "In1.Cu" signal)
		(6 "In2.Cu" signal)
		(8 "In3.Cu" signal)
		(10 "In4.Cu" signal)
		(12 "In5.Cu" signal)
		(14 "In6.Cu" signal)
		(2 "B.Cu" signal)
		(9 "F.Adhes" user "F.Adhesive")
		(11 "B.Adhes" user "B.Adhesive")
		(13 "F.Paste" user)
		(15 "B.Paste" user)
		(5 "F.SilkS" user "F.Silkscreen")
		(7 "B.SilkS" user "B.Silkscreen")
		(1 "F.Mask" user)
		(3 "B.Mask" user)
		(17 "Dwgs.User" user "User.Drawings")
		(19 "Cmts.User" user "User.Comments")
		(21 "Eco1.User" user "User.Eco1")
		(23 "Eco2.User" user "User.Eco2")
		(25 "Edge.Cuts" user)
		(27 "Margin" user)
		(31 "F.CrtYd" user "F.Courtyard")
		(29 "B.CrtYd" user "B.Courtyard")
		(35 "F.Fab" user)
		(33 "B.Fab" user)
	)
	(footprint "antmicro-footprints:Resonator_SMD_Abracon_ABM7_6x3.5x1.4mm"
		(layer "F.Cu")
		(at 97.18 86.8)
		(property "Reference" "Y1"
			(at -4.55 -1.02 0)
			(layer "F.SilkS")
			(effects
				(font
					(size 0.65 0.65)
					(thickness 0.15)
				)
				(justify left bottom)
			)
		)
		(property "Value" "Oscillator_SMD_27MHz_ABM7"
			(at -3 3 0)
			(layer "F.Fab")
			(hide yes)
			(effects
				(font
					(size 0.7 0.7)
					(thickness 0.15)
				)
				(justify left bottom)
			)
		)
		(property "Datasheet" "https://abracon.com/Resonators/abm7.pdf"
			(at 0 0 0)
			(layer "F.Fab")
			(hide yes)
			(effects
				(font
					(size 1.27 1.27)
					(thickness 0.15)
				)
			)
		)
		(property "Description" "Crystal, 27 MHz, SMD, 6mm x 3.5mm, 30 ppm, 18 pF, 20 ppm, ABM7"
			(at 0 0 0)
			(layer "F.Fab")
			(hide yes)
			(effects
				(font
					(size 1.27 1.27)
					(thickness 0.15)
				)
			)
		)
		(property "Author" "Antmicro"
			(at 0 0 0)
			(layer "F.Fab")
			(hide yes)
			(effects
				(font
					(size 1 1)
					(thickness 0.15)
				)
			)
		)
		(property "License" "Apache-2.0"
			(at 0 0 0)
			(layer "F.Fab")
			(hide yes)
			(effects
				(font
					(size 1 1)
					(thickness 0.15)
				)
			)
		)
		(property "MPN" "ABM7-27.000MHZ-D2Y-T"
			(at 0 0 0)
			(layer "F.Fab")
			(hide yes)
			(effects
				(font
					(size 1 1)
					(thickness 0.15)
				)
			)
		)
		(property "Manufacturer" "Abracon"
			(at 0 0 0)
			(layer "F.Fab")
			(hide yes)
			(effects
				(font
					(size 1 1)
					(thickness 0.15)
				)
			)
		)
		(property "Val" "27 MHz"
			(at 0 0 0)
			(unlocked yes)
			(layer "F.Fab")
			(hide yes)
			(effects
				(font
					(size 1 1)
					(thickness 0.15)
				)
			)
		)
		(sheetname "/SDI/")
		(sheetfile "sdi.kicad_sch")
		(attr smd)
		(fp_line
			(start -3.102 -1.4745)
			(end -2.803 -1.7755)
			(stroke
				(width 0.15)
				(type solid)
			)
			(layer "F.SilkS")
		)
		(fp_line
			(start -3.102 1.499)
			(end -2.801 1.8)
			(stroke
				(width 0.15)
				(type solid)
			)
			(layer "F.SilkS")
		)
		(fp_line
			(start -2.803 -1.7755)
			(end 2.798 -1.7755)
			(stroke
				(width 0.15)
				(type solid)
			)
			(layer "F.SilkS")
		)
		(fp_line
			(start 2.8 1.8)
			(end -2.801 1.8)
			(stroke
				(width 0.15)
				(type solid)
			)
			(layer "F.SilkS")
		)
		(fp_line
			(start 3.099 -1.4745)
			(end 2.798 -1.7755)
			(stroke
				(width 0.15)
				(type solid)
			)
			(layer "F.SilkS")
		)
		(fp_line
			(start 3.099 1.499)
			(end 2.8 1.8)
			(stroke
				(width 0.15)
				(type solid)
			)
			(layer "F.SilkS")
		)
		(fp_rect
			(start -3.251 -1.95)
			(end 3.248 1.949)
			(stroke
				(width 0.05)
				(type solid)
			)
			(fill no)
			(layer "F.CrtYd")
		)
		(pad "1" smd rect
			(at -2.15 0)
			(size 1.9 2.6)
			(layers "F.Cu" "F.Mask" "F.Paste")
			(net 45 "/SDI/XTAL1")
			(pintype "passive")
		)
		(pad "2" smd rect
			(at 2.148 0)
			(size 1.9 2.6)
			(layers "F.Cu" "F.Mask" "F.Paste")
			(net 46 "/SDI/XTAL2")
			(pintype "passive")
		)
	)
	(footprint "antmicro-footprints:R_0402_1005Metric"
		(layer "F.Cu")
		(at 128.75 116.75 -90)
		(descr "Resistor SMD 0402")
		(tags "resistor SMD 0402")
		(property "Reference" "R129"
			(at -0.81 -0.28 270)
			(layer "F.SilkS")
			(effects
				(font
					(size 0.65 0.65)
					(thickness 0.15)
				)
				(justify left bottom)
			)
		)
		(property "Value" "R_0R_0402"
			(at 0 1.4 270)
			(layer "F.Fab")
			(hide yes)
			(effects
				(font
					(size 0.7 0.7)
					(thickness 0.15)
				)
				(justify left bottom)
			)
		)
		(property "Datasheet" "https://industrial.panasonic.com/cdbs/www-data/pdf/RDA0000/AOA0000C301.pdf"
			(at 0 0 270)
			(layer "F.Fab")
			(hide yes)
			(effects
				(font
					(size 1.27 1.27)
					(thickness 0.15)
				)
			)
		)
		(property "Description" "SMD Chip Resistor, Jumper, 0 ohm, 100 mW, 0402 [1005 Metric], Thick Film, General Purpose"
			(at 0 0 270)
			(layer "F.Fab")
			(hide yes)
			(effects
				(font
					(size 1.27 1.27)
					(thickness 0.15)
				)
			)
		)
		(property "Author" "Antmicro"
			(at 12 245.5 0)
			(layer "F.Fab")
			(hide yes)
			(effects
				(font
					(size 1 1)
					(thickness 0.15)
				)
			)
		)
		(property "Current" "1A"
			(at 12 245.5 0)
			(layer "F.Fab")
			(hide yes)
			(effects
				(font
					(size 1 1)
					(thickness 0.15)
				)
			)
		)
		(property "License" "Apache-2.0"
			(at 12 245.5 0)
			(layer "F.Fab")
			(hide yes)
			(effects
				(font
					(size 1 1)
					(thickness 0.15)
				)
			)
		)
		(property "MPN" "ERJ2GE0R00X"
			(at 12 245.5 0)
			(layer "F.Fab")
			(hide yes)
			(effects
				(font
					(size 1 1)
					(thickness 0.15)
				)
			)
		)
		(property "Manufacturer" "Panasonic"
			(at 12 245.5 0)
			(layer "F.Fab")
			(hide yes)
			(effects
				(font
					(size 1 1)
					(thickness 0.15)
				)
			)
		)
		(property "Tolerance" "~"
			(at 12 245.5 0)
			(layer "F.Fab")
			(hide yes)
			(effects
				(font
					(size 1 1)
					(thickness 0.15)
				)
			)
		)
		(property "Val" "0R"
			(at 12 245.5 0)
			(layer "F.Fab")
			(hide yes)
			(effects
				(font
					(size 1 1)
					(thickness 0.15)
				)
			)
		)
		(sheetname "/Peripherals/")
		(sheetfile "peripherals.kicad_sch")
		(attr smd)
		(fp_rect
			(start -0.925 -0.47)
			(end 0.925 0.47)
			(stroke
				(width 0.05)
				(type default)
			)
			(fill no)
			(layer "F.CrtYd")
		)
		(fp_rect
			(start -0.5 -0.25)
			(end 0.5 0.25)
			(stroke
				(width 0.15)
				(type solid)
			)
			(fill no)
			(layer "F.Fab")
		)
		(fp_text user "Author: Antmicro"
			(at -0.95 4.169 270)
			(layer "F.Fab")
			(effects
				(font
					(size 0.7 0.7)
					(thickness 0.15)
				)
				(justify left bottom)
			)
		)
		(fp_text user "${REFERENCE}"
			(at -0.95 3.168 270)
			(layer "F.Fab")
			(effects
				(font
					(size 0.7 0.7)
					(thickness 0.15)
				)
				(justify left bottom)
			)
		)
		(fp_text user "License: Apache-2.0"
			(at -0.95 5.169 270)
			(layer "F.Fab")
			(effects
				(font
					(size 0.7 0.7)
					(thickness 0.15)
				)
				(justify left bottom)
			)
		)
		(pad "1" smd roundrect
			(at -0.48 0 270)
			(size 0.59 0.64)
			(layers "F.Cu" "F.Mask" "F.Paste")
			(roundrect_rratio 0.25)
			(net 107 "/Peripherals/FFC2_RESET")
			(pintype "passive")
		)
		(pad "2" smd roundrect
			(at 0.48 0 270)
			(size 0.59 0.64)
			(layers "F.Cu" "F.Mask" "F.Paste")
			(roundrect_rratio 0.25)
			(net 344 "Net-(J6-Pad33)")
			(pintype "passive")
		)
	)
	(footprint "antmicro-footprints:R_0402_1005Metric"
		(layer "F.Cu")
		(at 107.4 107.2 -90)
		(descr "Resistor SMD 0402")
		(tags "resistor SMD 0402")
		(property "Reference" "R142"
			(at 1.04 -0.33 90)
			(layer "F.SilkS")
			(effects
				(font
					(size 0.65 0.65)
					(thickness 0.15)
				)
				(justify right bottom)
			)
		)
		(property "Value" "R_0R_0402"
			(at 0 1.4 90)
			(layer "F.Fab")
			(hide yes)
			(effects
				(font
					(size 0.7 0.7)
					(thickness 0.15)
				)
				(justify right bottom)
			)
		)
		(property "Datasheet" "https://industrial.panasonic.com/cdbs/www-data/pdf/RDA0000/AOA0000C301.pdf"
			(at 0 0 270)
			(layer "F.Fab")
			(hide yes)
			(effects
				(font
					(size 1.27 1.27)
					(thickness 0.15)
				)
			)
		)
		(property "Description" "SMD Chip Resistor, Jumper, 0 ohm, 100 mW, 0402 [1005 Metric], Thick Film, General Purpose"
			(at 0 0 270)
			(layer "F.Fab")
			(hide yes)
			(effects
				(font
					(size 1.27 1.27)
					(thickness 0.15)
				)
			)
		)
		(property "Author" "Antmicro"
			(at 0.2 214.6 0)
			(layer "F.Fab")
			(hide yes)
			(effects
				(font
					(size 1 1)
					(thickness 0.15)
				)
			)
		)
		(property "Current" "1A"
			(at 0.2 214.6 0)
			(layer "F.Fab")
			(hide yes)
			(effects
				(font
					(size 1 1)
					(thickness 0.15)
				)
			)
		)
		(property "License" "Apache-2.0"
			(at 0.2 214.6 0)
			(layer "F.Fab")
			(hide yes)
			(effects
				(font
					(size 1 1)
					(thickness 0.15)
				)
			)
		)
		(property "MPN" "ERJ2GE0R00X"
			(at 0.2 214.6 0)
			(layer "F.Fab")
			(hide yes)
			(effects
				(font
					(size 1 1)
					(thickness 0.15)
				)
			)
		)
		(property "Manufacturer" "Panasonic"
			(at 0.2 214.6 0)
			(layer "F.Fab")
			(hide yes)
			(effects
				(font
					(size 1 1)
					(thickness 0.15)
				)
			)
		)
		(property "Tolerance" "~"
			(at 0.2 214.6 0)
			(layer "F.Fab")
			(hide yes)
			(effects
				(font
					(size 1 1)
					(thickness 0.15)
				)
			)
		)
		(property "Val" "0R"
			(at 0.2 214.6 0)
			(layer "F.Fab")
			(hide yes)
			(effects
				(font
					(size 1 1)
					(thickness 0.15)
				)
			)
		)
		(sheetname "/FPGA/")
		(sheetfile "fpga.kicad_sch")
		(attr smd)
		(fp_rect
			(start -0.925 -0.47)
			(end 0.925 0.47)
			(stroke
				(width 0.05)
				(type default)
			)
			(fill no)
			(layer "F.CrtYd")
		)
		(fp_rect
			(start -0.5 -0.25)
			(end 0.5 0.25)
			(stroke
				(width 0.15)
				(type solid)
			)
			(fill no)
			(layer "F.Fab")
		)
		(fp_text user "License: Apache-2.0"
			(at -0.95 5.169 270)
			(layer "F.Fab")
			(effects
				(font
					(size 0.7 0.7)
					(thickness 0.15)
				)
				(justify left bottom)
			)
		)
		(fp_text user "${REFERENCE}"
			(at -0.95 3.168 270)
			(layer "F.Fab")
			(effects
				(font
					(size 0.7 0.7)
					(thickness 0.15)
				)
				(justify left bottom)
			)
		)
		(fp_text user "Author: Antmicro"
			(at -0.95 4.169 270)
			(layer "F.Fab")
			(effects
				(font
					(size 0.7 0.7)
					(thickness 0.15)
				)
				(justify left bottom)
			)
		)
		(pad "1" smd roundrect
			(at -0.48 0 270)
			(size 0.59 0.64)
			(layers "F.Cu" "F.Mask" "F.Paste")
			(roundrect_rratio 0.25)
			(net 372 "Net-(U17-GPIO3{slash}~{SS3})")
			(pintype "passive")
		)
		(pad "2" smd roundrect
			(at 0.48 0 270)
			(size 0.59 0.64)
			(layers "F.Cu" "F.Mask" "F.Paste")
			(roundrect_rratio 0.25)
			(net 42 "/FPGA/INITN_SOFT")
			(pintype "passive")
		)
	)
)
